(kicad_pcb
	(version 20260206)
	(generator "pcbnew")
	(generator_version "10.0")
	(general
		(thickness 1.6)
		(legacy_teardrops no)
	)
	(paper "A4")
	(title_block
		(title "03242023_DA0F0TMBIJ0_F0T_Motherboard_J_brd_V01_OCP.brd")
		(comment 1 "Grand Teton / footprints 2635-2641 of 6105")
	)
	(layers
		(0 "F.Cu" signal "TOP")
		(4 "In1.Cu" signal "GND")
		(6 "In2.Cu" signal "IN1")
		(8 "In3.Cu" signal "GND1")
		(10 "In4.Cu" signal "IN2")
		(12 "In5.Cu" signal "GND2")
		(14 "In6.Cu" signal "IN3")
		(16 "In7.Cu" signal "GND3")
		(18 "In8.Cu" signal "VCC")
		(20 "In9.Cu" signal "VCC1")
		(22 "In10.Cu" signal "GND4")
		(24 "In11.Cu" signal "IN4")
		(26 "In12.Cu" signal "GND5")
		(28 "In13.Cu" signal "IN5")
		(30 "In14.Cu" signal "GND6")
		(32 "In15.Cu" signal "IN6")
		(34 "In16.Cu" signal "GND7")
		(2 "B.Cu" signal "BOTTOM")
		(9 "F.Adhes" user "F.Adhesive")
		(11 "B.Adhes" user "B.Adhesive")
		(13 "F.Paste" user "Package Geometry/Pastemask Top")
		(15 "B.Paste" user "Package Geometry/Pastemask Bottom")
		(5 "F.SilkS" user "Ref Des/Silkscreen Top")
		(7 "B.SilkS" user "Ref Des/Silkscreen Bottom")
		(1 "F.Mask" user "Board Geometry/Soldermask Top")
		(3 "B.Mask" user "Board Geometry/Soldermask Bottom")
		(17 "Dwgs.User" user "User.Drawings")
		(19 "Cmts.User" user "User.Comments")
		(21 "Eco1.User" user "User.Eco1")
		(23 "Eco2.User" user "User.Eco2")
		(25 "Edge.Cuts" user "Board Geometry/Outline")
		(27 "Margin" user)
		(31 "F.CrtYd" user "Package Geometry/Place Bound Top")
		(29 "B.CrtYd" user "Package Geometry/Place Bound Bottom")
		(35 "F.Fab" user "Ref Des/Assembly Top")
		(33 "B.Fab" user "Ref Des/Assembly Bottom")
	)
	(footprint ""
		(layer "F.Cu")
		(at 115.82908 -400.414998 90)
		(property "Reference" "C1802"
			(at 0 0 90)
			(layer "F.SilkS")
			(hide yes)
			(effects
				(font
					(size 1.27 1.27)
				)
			)
		)
		(property "Value" ""
			(at 0 0 90)
			(layer "F.Fab")
			(effects
				(font
					(size 1.27 1.27)
				)
			)
		)
		(duplicate_pad_numbers_are_jumpers no)
		(fp_line
			(start 0.7874 -0.4064)
			(end 0.7874 0.4064)
			(stroke
				(width 0.1524)
				(type default)
			)
			(layer "F.SilkS")
		)
		(fp_line
			(start -0.7874 -0.4064)
			(end 0.7874 -0.4064)
			(stroke
				(width 0.1524)
				(type default)
			)
			(layer "F.SilkS")
		)
		(fp_line
			(start 0.7874 0.4064)
			(end -0.7874 0.4064)
			(stroke
				(width 0.1524)
				(type default)
			)
			(layer "F.SilkS")
		)
		(fp_line
			(start -0.7874 0.4064)
			(end -0.7874 -0.4064)
			(stroke
				(width 0.1524)
				(type default)
			)
			(layer "F.SilkS")
		)
		(fp_line
			(start -0.12065 -0.305054)
			(end -0.12065 -0.2794)
			(stroke
				(width 0.1)
				(type default)
			)
			(layer "F.Fab")
		)
		(fp_line
			(start -0.67945 -0.305054)
			(end -0.12065 -0.305054)
			(stroke
				(width 0.1)
				(type default)
			)
			(layer "F.Fab")
		)
		(fp_line
			(start 0.67945 -0.3048)
			(end 0.67945 0.3048)
			(stroke
				(width 0.1)
				(type default)
			)
			(layer "F.Fab")
		)
		(fp_line
			(start 0.12065 -0.3048)
			(end 0.67945 -0.3048)
			(stroke
				(width 0.1)
				(type default)
			)
			(layer "F.Fab")
		)
		(fp_line
			(start 0.12065 -0.2794)
			(end 0.12065 -0.3048)
			(stroke
				(width 0.1)
				(type default)
			)
			(layer "F.Fab")
		)
		(fp_line
			(start -0.12065 -0.2794)
			(end 0.12065 -0.2794)
			(stroke
				(width 0.1)
				(type default)
			)
			(layer "F.Fab")
		)
		(fp_line
			(start 0.120396 0.2794)
			(end -0.12065 0.2794)
			(stroke
				(width 0.1)
				(type default)
			)
			(layer "F.Fab")
		)
		(fp_line
			(start -0.12065 0.2794)
			(end -0.12065 0.3048)
			(stroke
				(width 0.1)
				(type default)
			)
			(layer "F.Fab")
		)
		(fp_line
			(start 0.67945 0.3048)
			(end 0.120396 0.3048)
			(stroke
				(width 0.1)
				(type default)
			)
			(layer "F.Fab")
		)
		(fp_line
			(start 0.120396 0.3048)
			(end 0.120396 0.2794)
			(stroke
				(width 0.1)
				(type default)
			)
			(layer "F.Fab")
		)
		(fp_line
			(start -0.12065 0.3048)
			(end -0.67945 0.3048)
			(stroke
				(width 0.1)
				(type default)
			)
			(layer "F.Fab")
		)
		(fp_line
			(start -0.67945 0.3048)
			(end -0.67945 -0.305054)
			(stroke
				(width 0.1)
				(type default)
			)
			(layer "F.Fab")
		)
		(pad "1" smd circle
			(at -0.40005 0 90)
			(size 0 0)
			(layers "F.Cu" "F.Mask" "F.Paste")
			(net "FM_SMB_1_ALERT_GPU_ISO_N")
		)
		(pad "2" smd circle
			(at 0.40005 0 90)
			(size 0 0)
			(layers "F.Cu" "F.Mask" "F.Paste")
			(net "GND")
		)
	)
	(footprint ""
		(layer "F.Cu")
		(at 246.22506 -52.981606 90)
		(property "Reference" "PC2219"
			(at 0 0 90)
			(layer "F.SilkS")
			(hide yes)
			(effects
				(font
					(size 1.27 1.27)
				)
			)
		)
		(property "Value" ""
			(at 0 0 90)
			(layer "F.Fab")
			(effects
				(font
					(size 1.27 1.27)
				)
			)
		)
		(duplicate_pad_numbers_are_jumpers no)
		(fp_line
			(start 1.524 -0.762)
			(end 1.524 0.762)
			(stroke
				(width 0.1524)
				(type default)
			)
			(layer "F.SilkS")
		)
		(fp_line
			(start -1.524 -0.762)
			(end 1.524 -0.762)
			(stroke
				(width 0.1524)
				(type default)
			)
			(layer "F.SilkS")
		)
		(fp_line
			(start 1.524 0.762)
			(end -1.524 0.762)
			(stroke
				(width 0.1524)
				(type default)
			)
			(layer "F.SilkS")
		)
		(fp_line
			(start -1.524 0.762)
			(end -1.524 -0.762)
			(stroke
				(width 0.1524)
				(type default)
			)
			(layer "F.SilkS")
		)
		(fp_line
			(start 1.1049 -0.724916)
			(end -1.1049 -0.724916)
			(stroke
				(width 0.1)
				(type default)
			)
			(layer "F.Fab")
		)
		(fp_line
			(start -1.1049 -0.724916)
			(end -1.1049 0.724916)
			(stroke
				(width 0.1)
				(type default)
			)
			(layer "F.Fab")
		)
		(fp_line
			(start 1.1049 0.724916)
			(end 1.1049 -0.724916)
			(stroke
				(width 0.1)
				(type default)
			)
			(layer "F.Fab")
		)
		(fp_line
			(start -1.1049 0.724916)
			(end 1.1049 0.724916)
			(stroke
				(width 0.1)
				(type default)
			)
			(layer "F.Fab")
		)
		(pad "1" smd rect
			(at -0.889 0 270)
			(size 1.016 1.27)
			(layers "F.Cu" "F.Mask" "F.Paste")
			(net "P12V_E1S_0")
		)
		(pad "2" smd rect
			(at 0.889 0 270)
			(size 1.016 1.27)
			(layers "F.Cu" "F.Mask" "F.Paste")
			(net "GND")
		)
	)
	(footprint ""
		(layer "F.Cu")
		(at 450.43725 -43.155362)
		(property "Reference" "R3263"
			(at 0 0 0)
			(layer "F.SilkS")
			(hide yes)
			(effects
				(font
					(size 1.27 1.27)
				)
			)
		)
		(property "Value" ""
			(at 0 0 0)
			(layer "F.Fab")
			(effects
				(font
					(size 1.27 1.27)
				)
			)
		)
		(duplicate_pad_numbers_are_jumpers no)
		(fp_line
			(start -0.7874 -0.4064)
			(end 0.7874 -0.4064)
			(stroke
				(width 0.1524)
				(type default)
			)
			(layer "F.SilkS")
		)
		(fp_line
			(start -0.7874 0.4064)
			(end -0.7874 -0.4064)
			(stroke
				(width 0.1524)
				(type default)
			)
			(layer "F.SilkS")
		)
		(fp_line
			(start 0.7874 -0.4064)
			(end 0.7874 0.4064)
			(stroke
				(width 0.1524)
				(type default)
			)
			(layer "F.SilkS")
		)
		(fp_line
			(start 0.7874 0.4064)
			(end -0.7874 0.4064)
			(stroke
				(width 0.1524)
				(type default)
			)
			(layer "F.SilkS")
		)
		(fp_line
			(start -0.67945 -0.305054)
			(end -0.12065 -0.305054)
			(stroke
				(width 0.1)
				(type default)
			)
			(layer "F.Fab")
		)
		(fp_line
			(start -0.67945 0.3048)
			(end -0.67945 -0.305054)
			(stroke
				(width 0.1)
				(type default)
			)
			(layer "F.Fab")
		)
		(fp_line
			(start -0.12065 -0.305054)
			(end -0.12065 -0.2794)
			(stroke
				(width 0.1)
				(type default)
			)
			(layer "F.Fab")
		)
		(fp_line
			(start -0.12065 -0.2794)
			(end 0.12065 -0.2794)
			(stroke
				(width 0.1)
				(type default)
			)
			(layer "F.Fab")
		)
		(fp_line
			(start -0.12065 0.2794)
			(end -0.12065 0.3048)
			(stroke
				(width 0.1)
				(type default)
			)
			(layer "F.Fab")
		)
		(fp_line
			(start -0.12065 0.3048)
			(end -0.67945 0.3048)
			(stroke
				(width 0.1)
				(type default)
			)
			(layer "F.Fab")
		)
		(fp_line
			(start 0.120396 0.2794)
			(end -0.12065 0.2794)
			(stroke
				(width 0.1)
				(type default)
			)
			(layer "F.Fab")
		)
		(fp_line
			(start 0.120396 0.3048)
			(end 0.120396 0.2794)
			(stroke
				(width 0.1)
				(type default)
			)
			(layer "F.Fab")
		)
		(fp_line
			(start 0.12065 -0.3048)
			(end 0.67945 -0.3048)
			(stroke
				(width 0.1)
				(type default)
			)
			(layer "F.Fab")
		)
		(fp_line
			(start 0.12065 -0.2794)
			(end 0.12065 -0.3048)
			(stroke
				(width 0.1)
				(type default)
			)
			(layer "F.Fab")
		)
		(fp_line
			(start 0.67945 -0.3048)
			(end 0.67945 0.3048)
			(stroke
				(width 0.1)
				(type default)
			)
			(layer "F.Fab")
		)
		(fp_line
			(start 0.67945 0.3048)
			(end 0.120396 0.3048)
			(stroke
				(width 0.1)
				(type default)
			)
			(layer "F.Fab")
		)
		(pad "1" smd circle
			(at -0.40005 0)
			(size 0 0)
			(layers "F.Cu" "F.Mask" "F.Paste")
			(net "HP_LVC3_OCP_V3_1_R_EN")
		)
		(pad "2" smd circle
			(at 0.40005 0)
			(size 0 0)
			(layers "F.Cu" "F.Mask" "F.Paste")
			(net "HP_LVC3_OCP_V3_1_EN")
		)
	)
	(footprint ""
		(layer "F.Cu")
		(at 498.58549 -470.89187)
		(property "Reference" "U2_BP"
			(at -1.6764 -1.07823 0)
			(unlocked yes)
			(layer "F.SilkS")
			(effects
				(font
					(size 0.7874 0.5842)
					(thickness 0.1524)
				)
				(justify left)
			)
		)
		(property "Value" ""
			(at 0 0 0)
			(layer "F.Fab")
			(effects
				(font
					(size 1.27 1.27)
				)
			)
		)
		(duplicate_pad_numbers_are_jumpers no)
		(pad "1" smd circle
			(at 0 0)
			(size 0.762 0.762)
			(layers "F.Cu" "F.Mask" "F.Paste")
			(net "Net_8484")
		)
	)
	(footprint ""
		(layer "F.Cu")
		(at 409.65628 -149.037548)
		(property "Reference" "PC181"
			(at 0 0 0)
			(layer "F.SilkS")
			(hide yes)
			(effects
				(font
					(size 1.27 1.27)
				)
			)
		)
		(property "Value" ""
			(at 0 0 0)
			(layer "F.Fab")
			(effects
				(font
					(size 1.27 1.27)
				)
			)
		)
		(duplicate_pad_numbers_are_jumpers no)
		(fp_line
			(start -0.7874 -0.4064)
			(end 0.7874 -0.4064)
			(stroke
				(width 0.1524)
				(type default)
			)
			(layer "F.SilkS")
		)
		(fp_line
			(start -0.7874 0.4064)
			(end -0.7874 -0.4064)
			(stroke
				(width 0.1524)
				(type default)
			)
			(layer "F.SilkS")
		)
		(fp_line
			(start 0.7874 -0.4064)
			(end 0.7874 0.4064)
			(stroke
				(width 0.1524)
				(type default)
			)
			(layer "F.SilkS")
		)
		(fp_line
			(start 0.7874 0.4064)
			(end -0.7874 0.4064)
			(stroke
				(width 0.1524)
				(type default)
			)
			(layer "F.SilkS")
		)
		(fp_line
			(start -0.67945 -0.305054)
			(end -0.12065 -0.305054)
			(stroke
				(width 0.1)
				(type default)
			)
			(layer "F.Fab")
		)
		(fp_line
			(start -0.67945 0.3048)
			(end -0.67945 -0.305054)
			(stroke
				(width 0.1)
				(type default)
			)
			(layer "F.Fab")
		)
		(fp_line
			(start -0.12065 -0.305054)
			(end -0.12065 -0.2794)
			(stroke
				(width 0.1)
				(type default)
			)
			(layer "F.Fab")
		)
		(fp_line
			(start -0.12065 -0.2794)
			(end 0.12065 -0.2794)
			(stroke
				(width 0.1)
				(type default)
			)
			(layer "F.Fab")
		)
		(fp_line
			(start -0.12065 0.2794)
			(end -0.12065 0.3048)
			(stroke
				(width 0.1)
				(type default)
			)
			(layer "F.Fab")
		)
		(fp_line
			(start -0.12065 0.3048)
			(end -0.67945 0.3048)
			(stroke
				(width 0.1)
				(type default)
			)
			(layer "F.Fab")
		)
		(fp_line
			(start 0.120396 0.2794)
			(end -0.12065 0.2794)
			(stroke
				(width 0.1)
				(type default)
			)
			(layer "F.Fab")
		)
		(fp_line
			(start 0.120396 0.3048)
			(end 0.120396 0.2794)
			(stroke
				(width 0.1)
				(type default)
			)
			(layer "F.Fab")
		)
		(fp_line
			(start 0.12065 -0.3048)
			(end 0.67945 -0.3048)
			(stroke
				(width 0.1)
				(type default)
			)
			(layer "F.Fab")
		)
		(fp_line
			(start 0.12065 -0.2794)
			(end 0.12065 -0.3048)
			(stroke
				(width 0.1)
				(type default)
			)
			(layer "F.Fab")
		)
		(fp_line
			(start 0.67945 -0.3048)
			(end 0.67945 0.3048)
			(stroke
				(width 0.1)
				(type default)
			)
			(layer "F.Fab")
		)
		(fp_line
			(start 0.67945 0.3048)
			(end 0.120396 0.3048)
			(stroke
				(width 0.1)
				(type default)
			)
			(layer "F.Fab")
		)
		(pad "1" smd circle
			(at -0.40005 0)
			(size 0 0)
			(layers "F.Cu" "F.Mask" "F.Paste")
			(net "PVCCFA_EHV_CPU0")
		)
		(pad "2" smd circle
			(at 0.40005 0)
			(size 0 0)
			(layers "F.Cu" "F.Mask" "F.Paste")
			(net "GND")
		)
	)
	(footprint ""
		(layer "F.Cu")
		(at 430.600104 -131.599178 180)
		(property "Reference" "R2390"
			(at 0 0 180)
			(layer "F.SilkS")
			(hide yes)
			(effects
				(font
					(size 1.27 1.27)
				)
			)
		)
		(property "Value" ""
			(at 0 0 180)
			(layer "F.Fab")
			(effects
				(font
					(size 1.27 1.27)
				)
			)
		)
		(duplicate_pad_numbers_are_jumpers no)
		(fp_line
			(start 0.7874 0.4064)
			(end -0.7874 0.4064)
			(stroke
				(width 0.1524)
				(type default)
			)
			(layer "F.SilkS")
		)
		(fp_line
			(start 0.7874 -0.4064)
			(end 0.7874 0.4064)
			(stroke
				(width 0.1524)
				(type default)
			)
			(layer "F.SilkS")
		)
		(fp_line
			(start -0.7874 0.4064)
			(end -0.7874 -0.4064)
			(stroke
				(width 0.1524)
				(type default)
			)
			(layer "F.SilkS")
		)
		(fp_line
			(start -0.7874 -0.4064)
			(end 0.7874 -0.4064)
			(stroke
				(width 0.1524)
				(type default)
			)
			(layer "F.SilkS")
		)
		(fp_line
			(start 0.67945 0.3048)
			(end 0.120396 0.3048)
			(stroke
				(width 0.1)
				(type default)
			)
			(layer "F.Fab")
		)
		(fp_line
			(start 0.67945 -0.3048)
			(end 0.67945 0.3048)
			(stroke
				(width 0.1)
				(type default)
			)
			(layer "F.Fab")
		)
		(fp_line
			(start 0.12065 -0.2794)
			(end 0.12065 -0.3048)
			(stroke
				(width 0.1)
				(type default)
			)
			(layer "F.Fab")
		)
		(fp_line
			(start 0.12065 -0.3048)
			(end 0.67945 -0.3048)
			(stroke
				(width 0.1)
				(type default)
			)
			(layer "F.Fab")
		)
		(fp_line
			(start 0.120396 0.3048)
			(end 0.120396 0.2794)
			(stroke
				(width 0.1)
				(type default)
			)
			(layer "F.Fab")
		)
		(fp_line
			(start 0.120396 0.2794)
			(end -0.12065 0.2794)
			(stroke
				(width 0.1)
				(type default)
			)
			(layer "F.Fab")
		)
		(fp_line
			(start -0.12065 0.3048)
			(end -0.67945 0.3048)
			(stroke
				(width 0.1)
				(type default)
			)
			(layer "F.Fab")
		)
		(fp_line
			(start -0.12065 0.2794)
			(end -0.12065 0.3048)
			(stroke
				(width 0.1)
				(type default)
			)
			(layer "F.Fab")
		)
		(fp_line
			(start -0.12065 -0.2794)
			(end 0.12065 -0.2794)
			(stroke
				(width 0.1)
				(type default)
			)
			(layer "F.Fab")
		)
		(fp_line
			(start -0.12065 -0.305054)
			(end -0.12065 -0.2794)
			(stroke
				(width 0.1)
				(type default)
			)
			(layer "F.Fab")
		)
		(fp_line
			(start -0.67945 0.3048)
			(end -0.67945 -0.305054)
			(stroke
				(width 0.1)
				(type default)
			)
			(layer "F.Fab")
		)
		(fp_line
			(start -0.67945 -0.305054)
			(end -0.12065 -0.305054)
			(stroke
				(width 0.1)
				(type default)
			)
			(layer "F.Fab")
		)
		(pad "1" smd circle
			(at -0.40005 0 180)
			(size 0 0)
			(layers "F.Cu" "F.Mask" "F.Paste")
			(net "SMB_VR_3V3AUX_SCL_R2")
		)
		(pad "2" smd circle
			(at 0.40005 0 180)
			(size 0 0)
			(layers "F.Cu" "F.Mask" "F.Paste")
			(net "SMB_CLK_PVCCINFAON_CPU0")
		)
	)
	(footprint ""
		(layer "F.Cu")
		(at 228.764592 -125.297946 180)
		(property "Reference" "R565"
			(at 0 0 180)
			(layer "F.SilkS")
			(hide yes)
			(effects
				(font
					(size 1.27 1.27)
				)
			)
		)
		(property "Value" ""
			(at 0 0 180)
			(layer "F.Fab")
			(effects
				(font
					(size 1.27 1.27)
				)
			)
		)
		(duplicate_pad_numbers_are_jumpers no)
		(fp_line
			(start 0.7874 0.4064)
			(end -0.7874 0.4064)
			(stroke
				(width 0.1524)
				(type default)
			)
			(layer "F.SilkS")
		)
		(fp_line
			(start 0.7874 -0.050546)
			(end 0.7874 0.4064)
			(stroke
				(width 0.1524)
				(type default)
			)
			(layer "F.SilkS")
		)
		(fp_line
			(start -0.429768 -0.4064)
			(end 0.520192 -0.4064)
			(stroke
				(width 0.1524)
				(type default)
			)
			(layer "F.SilkS")
		)
		(fp_line
			(start -0.7874 0.4064)
			(end -0.7874 -0.083566)
			(stroke
				(width 0.1524)
				(type default)
			)
			(layer "F.SilkS")
		)
		(fp_line
			(start 0.67945 0.3048)
			(end 0.120396 0.3048)
			(stroke
				(width 0.1)
				(type default)
			)
			(layer "F.Fab")
		)
		(fp_line
			(start 0.67945 -0.3048)
			(end 0.67945 0.3048)
			(stroke
				(width 0.1)
				(type default)
			)
			(layer "F.Fab")
		)
		(fp_line
			(start 0.12065 -0.2794)
			(end 0.12065 -0.3048)
			(stroke
				(width 0.1)
				(type default)
			)
			(layer "F.Fab")
		)
		(fp_line
			(start 0.12065 -0.3048)
			(end 0.67945 -0.3048)
			(stroke
				(width 0.1)
				(type default)
			)
			(layer "F.Fab")
		)
		(fp_line
			(start 0.120396 0.3048)
			(end 0.120396 0.2794)
			(stroke
				(width 0.1)
				(type default)
			)
			(layer "F.Fab")
		)
		(fp_line
			(start 0.120396 0.2794)
			(end -0.12065 0.2794)
			(stroke
				(width 0.1)
				(type default)
			)
			(layer "F.Fab")
		)
		(fp_line
			(start -0.12065 0.3048)
			(end -0.67945 0.3048)
			(stroke
				(width 0.1)
				(type default)
			)
			(layer "F.Fab")
		)
		(fp_line
			(start -0.12065 0.2794)
			(end -0.12065 0.3048)
			(stroke
				(width 0.1)
				(type default)
			)
			(layer "F.Fab")
		)
		(fp_line
			(start -0.12065 -0.2794)
			(end 0.12065 -0.2794)
			(stroke
				(width 0.1)
				(type default)
			)
			(layer "F.Fab")
		)
		(fp_line
			(start -0.12065 -0.305054)
			(end -0.12065 -0.2794)
			(stroke
				(width 0.1)
				(type default)
			)
			(layer "F.Fab")
		)
		(fp_line
			(start -0.67945 0.3048)
			(end -0.67945 -0.305054)
			(stroke
				(width 0.1)
				(type default)
			)
			(layer "F.Fab")
		)
		(fp_line
			(start -0.67945 -0.305054)
			(end -0.12065 -0.305054)
			(stroke
				(width 0.1)
				(type default)
			)
			(layer "F.Fab")
		)
		(pad "1" smd circle
			(at -0.40005 0 180)
			(size 0 0)
			(layers "F.Cu" "F.Mask" "F.Paste")
			(net "CLK_100M_OCP_SFF_1_R_DP")
		)
		(pad "2" smd circle
			(at 0.40005 0 180)
			(size 0 0)
			(layers "F.Cu" "F.Mask" "F.Paste")
			(net "CLK_100M_OCP_SFF_1_DP")
		)
	)
)
